# T6G (Grand Teton) — schematic netlist excerpt (pin names and nets, part order shuffled) for the footprints in the layout excerpt that follows; sources: Cadence DE-HDL packaged netlist, KiCad conversion of 04192023_DAF0TMB3IC0_F0TG_MB_C_brd_V02_OCP.brd

C1347  Q_CAP  0.1UF 25V 10% X7R  pkg 0402  page 257 : A = MAX11617_VREF ; B = GND
R931  Q_RES  0 5% CHIP  pkg 0402LF  page 54 : A = CPU1_XTRIG_L6 ; B = CPU1_XTRIG_R1_L6

(kicad_pcb
	(version 20260206)
	(generator "pcbnew")
	(generator_version "10.0")
	(general
		(thickness 1.6)
		(legacy_teardrops no)
	)
	(paper "A4")
	(title_block
		(title "04192023_DAF0TMB3IC0_F0TG_MB_C_brd_V02_OCP.brd")
		(comment 1 "Grand Teton / footprints 1592-1593 of 8354")
	)
	(layers
		(0 "F.Cu" signal "TOP")
		(4 "In1.Cu" signal "GND")
		(6 "In2.Cu" signal "IN1")
		(8 "In3.Cu" signal "GND1")
		(10 "In4.Cu" signal "IN2")
		(12 "In5.Cu" signal "GND2")
		(14 "In6.Cu" signal "IN3")
		(16 "In7.Cu" signal "GND3")
		(18 "In8.Cu" signal "VCC")
		(20 "In9.Cu" signal "VCC1")
		(22 "In10.Cu" signal "GND4")
		(24 "In11.Cu" signal "IN4")
		(26 "In12.Cu" signal "GND5")
		(28 "In13.Cu" signal "IN5")
		(30 "In14.Cu" signal "GND6")
		(32 "In15.Cu" signal "IN6")
		(34 "In16.Cu" signal "GND7")
		(2 "B.Cu" signal "BOTTOM")
		(9 "F.Adhes" user "F.Adhesive")
		(11 "B.Adhes" user "B.Adhesive")
		(13 "F.Paste" user "Package Geometry/Pastemask Top")
		(15 "B.Paste" user "Package Geometry/Pastemask Bottom")
		(5 "F.SilkS" user "Ref Des/Silkscreen Top")
		(7 "B.SilkS" user "Ref Des/Silkscreen Bottom")
		(1 "F.Mask" user "Board Geometry/Soldermask Top")
		(3 "B.Mask" user "Board Geometry/Soldermask Bottom")
		(17 "Dwgs.User" user "User.Drawings")
		(19 "Cmts.User" user "User.Comments")
		(21 "Eco1.User" user "User.Eco1")
		(23 "Eco2.User" user "User.Eco2")
		(25 "Edge.Cuts" user "Board Geometry/Outline")
		(27 "Margin" user)
		(31 "F.CrtYd" user "Package Geometry/Place Bound Top")
		(29 "B.CrtYd" user "Package Geometry/Place Bound Bottom")
		(35 "F.Fab" user "Ref Des/Assembly Top")
		(33 "B.Fab" user "Ref Des/Assembly Bottom")
	)
	(footprint ""
		(layer "F.Cu")
		(at 313.104022 -36.890706 180)
		(property "Reference" "C1347"
			(at 0 0 180)
			(layer "F.SilkS")
			(hide yes)
			(effects
				(font
					(size 1.27 1.27)
				)
			)
		)
		(property "Value" ""
			(at 0 0 180)
			(layer "F.Fab")
			(effects
				(font
					(size 1.27 1.27)
				)
			)
		)
		(duplicate_pad_numbers_are_jumpers no)
		(fp_line
			(start 0.7874 0.4064)
			(end -0.7874 0.4064)
			(stroke
				(width 0.1524)
				(type default)
			)
			(layer "F.SilkS")
		)
		(fp_line
			(start 0.7874 -0.4064)
			(end 0.7874 0.4064)
			(stroke
				(width 0.1524)
				(type default)
			)
			(layer "F.SilkS")
		)
		(fp_line
			(start -0.7874 0.4064)
			(end -0.7874 -0.4064)
			(stroke
				(width 0.1524)
				(type default)
			)
			(layer "F.SilkS")
		)
		(fp_line
			(start -0.7874 -0.4064)
			(end 0.7874 -0.4064)
			(stroke
				(width 0.1524)
				(type default)
			)
			(layer "F.SilkS")
		)
		(fp_line
			(start 0.67945 0.3048)
			(end 0.120396 0.3048)
			(stroke
				(width 0.1)
				(type default)
			)
			(layer "F.Fab")
		)
		(fp_line
			(start 0.67945 -0.3048)
			(end 0.67945 0.3048)
			(stroke
				(width 0.1)
				(type default)
			)
			(layer "F.Fab")
		)
		(fp_line
			(start 0.12065 -0.2794)
			(end 0.12065 -0.3048)
			(stroke
				(width 0.1)
				(type default)
			)
			(layer "F.Fab")
		)
		(fp_line
			(start 0.12065 -0.3048)
			(end 0.67945 -0.3048)
			(stroke
				(width 0.1)
				(type default)
			)
			(layer "F.Fab")
		)
		(fp_line
			(start 0.120396 0.3048)
			(end 0.120396 0.2794)
			(stroke
				(width 0.1)
				(type default)
			)
			(layer "F.Fab")
		)
		(fp_line
			(start 0.120396 0.2794)
			(end -0.12065 0.2794)
			(stroke
				(width 0.1)
				(type default)
			)
			(layer "F.Fab")
		)
		(fp_line
			(start -0.12065 0.3048)
			(end -0.67945 0.3048)
			(stroke
				(width 0.1)
				(type default)
			)
			(layer "F.Fab")
		)
		(fp_line
			(start -0.12065 0.2794)
			(end -0.12065 0.3048)
			(stroke
				(width 0.1)
				(type default)
			)
			(layer "F.Fab")
		)
		(fp_line
			(start -0.12065 -0.2794)
			(end 0.12065 -0.2794)
			(stroke
				(width 0.1)
				(type default)
			)
			(layer "F.Fab")
		)
		(fp_line
			(start -0.12065 -0.305054)
			(end -0.12065 -0.2794)
			(stroke
				(width 0.1)
				(type default)
			)
			(layer "F.Fab")
		)
		(fp_line
			(start -0.67945 0.3048)
			(end -0.67945 -0.305054)
			(stroke
				(width 0.1)
				(type default)
			)
			(layer "F.Fab")
		)
		(fp_line
			(start -0.67945 -0.305054)
			(end -0.12065 -0.305054)
			(stroke
				(width 0.1)
				(type default)
			)
			(layer "F.Fab")
		)
		(pad "1" smd circle
			(at -0.40005 0 180)
			(size 0 0)
			(layers "F.Cu" "F.Mask" "F.Paste")
			(net "MAX11617_VREF")
		)
		(pad "2" smd circle
			(at 0.40005 0 180)
			(size 0 0)
			(layers "F.Cu" "F.Mask" "F.Paste")
			(net "GND")
		)
	)
	(footprint ""
		(layer "F.Cu")
		(at 2.992628 -44.062904 90)
		(property "Reference" "R931"
			(at 0 0 90)
			(layer "F.SilkS")
			(hide yes)
			(effects
				(font
					(size 1.27 1.27)
				)
			)
		)
		(property "Value" ""
			(at 0 0 90)
			(layer "F.Fab")
			(effects
				(font
					(size 1.27 1.27)
				)
			)
		)
		(duplicate_pad_numbers_are_jumpers no)
		(fp_line
			(start 0.7874 -0.4064)
			(end 0.7874 0.4064)
			(stroke
				(width 0.1524)
				(type default)
			)
			(layer "F.SilkS")
		)
		(fp_line
			(start -0.7874 -0.4064)
			(end 0.7874 -0.4064)
			(stroke
				(width 0.1524)
				(type default)
			)
			(layer "F.SilkS")
		)
		(fp_line
			(start 0.7874 0.4064)
			(end -0.7874 0.4064)
			(stroke
				(width 0.1524)
				(type default)
			)
			(layer "F.SilkS")
		)
		(fp_line
			(start -0.7874 0.4064)
			(end -0.7874 -0.4064)
			(stroke
				(width 0.1524)
				(type default)
			)
			(layer "F.SilkS")
		)
		(fp_line
			(start -0.12065 -0.305054)
			(end -0.12065 -0.2794)
			(stroke
				(width 0.1)
				(type default)
			)
			(layer "F.Fab")
		)
		(fp_line
			(start -0.67945 -0.305054)
			(end -0.12065 -0.305054)
			(stroke
				(width 0.1)
				(type default)
			)
			(layer "F.Fab")
		)
		(fp_line
			(start 0.67945 -0.3048)
			(end 0.67945 0.3048)
			(stroke
				(width 0.1)
				(type default)
			)
			(layer "F.Fab")
		)
		(fp_line
			(start 0.12065 -0.3048)
			(end 0.67945 -0.3048)
			(stroke
				(width 0.1)
				(type default)
			)
			(layer "F.Fab")
		)
		(fp_line
			(start 0.12065 -0.2794)
			(end 0.12065 -0.3048)
			(stroke
				(width 0.1)
				(type default)
			)
			(layer "F.Fab")
		)
		(fp_line
			(start -0.12065 -0.2794)
			(end 0.12065 -0.2794)
			(stroke
				(width 0.1)
				(type default)
			)
			(layer "F.Fab")
		)
		(fp_line
			(start 0.120396 0.2794)
			(end -0.12065 0.2794)
			(stroke
				(width 0.1)
				(type default)
			)
			(layer "F.Fab")
		)
		(fp_line
			(start -0.12065 0.2794)
			(end -0.12065 0.3048)
			(stroke
				(width 0.1)
				(type default)
			)
			(layer "F.Fab")
		)
		(fp_line
			(start 0.67945 0.3048)
			(end 0.120396 0.3048)
			(stroke
				(width 0.1)
				(type default)
			)
			(layer "F.Fab")
		)
		(fp_line
			(start 0.120396 0.3048)
			(end 0.120396 0.2794)
			(stroke
				(width 0.1)
				(type default)
			)
			(layer "F.Fab")
		)
		(fp_line
			(start -0.12065 0.3048)
			(end -0.67945 0.3048)
			(stroke
				(width 0.1)
				(type default)
			)
			(layer "F.Fab")
		)
		(fp_line
			(start -0.67945 0.3048)
			(end -0.67945 -0.305054)
			(stroke
				(width 0.1)
				(type default)
			)
			(layer "F.Fab")
		)
		(pad "1" smd circle
			(at -0.40005 0 90)
			(size 0 0)
			(layers "F.Cu" "F.Mask" "F.Paste")
			(net "CPU1_XTRIG_L6")
		)
		(pad "2" smd circle
			(at 0.40005 0 90)
			(size 0 0)
			(layers "F.Cu" "F.Mask" "F.Paste")
			(net "CPU1_XTRIG_R1_L6")
		)
	)
)
